(kicad_pcb
	(version 20241229)
	(generator "pcbnew")
	(generator_version "9.0")
	(general
		(thickness 1.711)
		(legacy_teardrops no)
	)
	(paper "A4")
	(title_block
		(title "Antmicro Baseboard for Jetson AGX Thor")
		(date "2026-02-18")
		(rev "1.1.0")
		(company "Antmicro Ltd")
		(comment 1 "www.antmicro.com")
		(comment 9 "footprints 972-974 of 1170")
	)
	(layers
		(0 "F.Cu" signal)
		(4 "In1.Cu" signal)
		(6 "In2.Cu" signal)
		(8 "In3.Cu" signal)
		(10 "In4.Cu" jumper)
		(12 "In5.Cu" signal)
		(14 "In6.Cu" signal)
		(16 "In7.Cu" signal)
		(18 "In8.Cu" signal)
		(2 "B.Cu" signal)
		(9 "F.Adhes" user "F.Adhesive")
		(11 "B.Adhes" user "B.Adhesive")
		(13 "F.Paste" user)
		(15 "B.Paste" user)
		(5 "F.SilkS" user "F.Silkscreen")
		(7 "B.SilkS" user "B.Silkscreen")
		(1 "F.Mask" user)
		(3 "B.Mask" user)
		(17 "Dwgs.User" user "User.Drawings")
		(19 "Cmts.User" user "User.Comments")
		(21 "Eco1.User" user "User.Eco1")
		(23 "Eco2.User" user "User.Eco2")
		(25 "Edge.Cuts" user)
		(27 "Margin" user)
		(31 "F.CrtYd" user "F.Courtyard")
		(29 "B.CrtYd" user "B.Courtyard")
		(35 "F.Fab" user)
		(33 "B.Fab" user)
	)
	(footprint "antmicro-footprints:QFN-2L_1.6x1x0.55mm"
		(layer "B.Cu")
		(at 230.87 90.2 180)
		(property "Reference" "D22"
			(at 1.2 -0.7 0)
			(layer "B.SilkS")
			(effects
				(font
					(size 0.7 0.7)
					(thickness 0.15)
				)
				(justify left bottom mirror)
			)
		)
		(property "Value" "ESDA25P35-1U1M"
			(at 0 -1.7 0)
			(layer "B.Fab")
			(effects
				(font
					(size 0.7 0.7)
					(thickness 0.15)
				)
				(justify left bottom mirror)
			)
		)
		(property "Datasheet" "https://www.st.com/resource/en/datasheet/esda25p35-1u1m.pdf"
			(at 0 0 0)
			(layer "B.Fab")
			(hide yes)
			(effects
				(font
					(size 1.27 1.27)
					(thickness 0.15)
				)
				(justify mirror)
			)
		)
		(property "Description" "Unidirectional TVS, 30 kV, QFN-2L, 22 V, 195 pF"
			(at 0 0 0)
			(layer "B.Fab")
			(hide yes)
			(effects
				(font
					(size 1.27 1.27)
					(thickness 0.15)
				)
				(justify mirror)
			)
		)
		(property "Manufacturer" "STMicroelectronics"
			(at 0 0 180)
			(unlocked yes)
			(layer "B.Fab")
			(hide yes)
			(effects
				(font
					(size 1 1)
					(thickness 0.15)
				)
				(justify mirror)
			)
		)
		(property "MPN" "ESDA25P35-1U1M"
			(at 0 0 180)
			(unlocked yes)
			(layer "B.Fab")
			(hide yes)
			(effects
				(font
					(size 1 1)
					(thickness 0.15)
				)
				(justify mirror)
			)
		)
		(property "Author" "Antmicro"
			(at 0 0 180)
			(unlocked yes)
			(layer "B.Fab")
			(hide yes)
			(effects
				(font
					(size 1 1)
					(thickness 0.15)
				)
				(justify mirror)
			)
		)
		(property "License" "Apache-2.0"
			(at 0 0 180)
			(unlocked yes)
			(layer "B.Fab")
			(hide yes)
			(effects
				(font
					(size 1 1)
					(thickness 0.15)
				)
				(justify mirror)
			)
		)
		(sheetname "/USB DP Alt mode/")
		(sheetfile "usb_dp.kicad_sch")
		(attr smd)
		(fp_line
			(start 0.23 0.45)
			(end -0.23 0.45)
			(stroke
				(width 0.15)
				(type solid)
			)
			(layer "B.SilkS")
		)
		(fp_line
			(start 0.23 -0.45)
			(end -0.23 -0.45)
			(stroke
				(width 0.15)
				(type solid)
			)
			(layer "B.SilkS")
		)
		(fp_line
			(start -1.2 0.4)
			(end -1.2 -0.4)
			(stroke
				(width 0.15)
				(type solid)
			)
			(layer "B.SilkS")
		)
		(fp_rect
			(start 1.25 -0.65)
			(end -1.25 0.65)
			(stroke
				(width 0.05)
				(type solid)
			)
			(fill no)
			(layer "B.CrtYd")
		)
		(fp_line
			(start 0.599 0)
			(end 0.201 0)
			(stroke
				(width 0.15)
				(type solid)
			)
			(layer "B.Fab")
		)
		(fp_line
			(start 0.201 0.202)
			(end -0.101 0)
			(stroke
				(width 0.15)
				(type solid)
			)
			(layer "B.Fab")
		)
		(fp_line
			(start 0.201 0)
			(end 0.201 0.202)
			(stroke
				(width 0.15)
				(type solid)
			)
			(layer "B.Fab")
		)
		(fp_line
			(start 0.201 -0.2)
			(end 0.201 0)
			(stroke
				(width 0.15)
				(type solid)
			)
			(layer "B.Fab")
		)
		(fp_line
			(start -0.101 0)
			(end 0.201 -0.2)
			(stroke
				(width 0.15)
				(type solid)
			)
			(layer "B.Fab")
		)
		(fp_line
			(start -0.199 0.202)
			(end -0.199 -0.1)
			(stroke
				(width 0.15)
				(type solid)
			)
			(layer "B.Fab")
		)
		(fp_line
			(start -0.199 0)
			(end -0.597 0)
			(stroke
				(width 0.15)
				(type solid)
			)
			(layer "B.Fab")
		)
		(fp_line
			(start -0.199 -0.2)
			(end -0.199 -0.1)
			(stroke
				(width 0.15)
				(type solid)
			)
			(layer "B.Fab")
		)
		(fp_rect
			(start 0.848 -0.4)
			(end -0.85 0.402)
			(stroke
				(width 0.15)
				(type solid)
			)
			(fill no)
			(layer "B.Fab")
		)
		(fp_text user "Author: Antmicro"
			(at -1.31 -4.769 0)
			(layer "B.Fab")
			(effects
				(font
					(size 0.7 0.7)
					(thickness 0.15)
				)
				(justify left bottom mirror)
			)
		)
		(fp_text user "License: Apache-2.0"
			(at -1.31 -5.769 0)
			(layer "B.Fab")
			(effects
				(font
					(size 0.7 0.7)
					(thickness 0.15)
				)
				(justify left bottom mirror)
			)
		)
		(fp_text user "${REFERENCE}"
			(at -1.31 -3.769 0)
			(layer "B.Fab")
			(effects
				(font
					(size 0.7 0.7)
					(thickness 0.15)
				)
				(justify left bottom mirror)
			)
		)
		(pad "1" smd roundrect
			(at -0.7 0)
			(size 0.8 1)
			(layers "B.Cu" "B.Mask" "B.Paste")
			(roundrect_rratio 0.2)
			(net 376 "/USB DP Alt mode/USBC1_VBUS")
			(pinfunction "C")
			(pintype "passive")
		)
		(pad "2" smd roundrect
			(at 0.7 0)
			(size 0.8 1)
			(layers "B.Cu" "B.Mask" "B.Paste")
			(roundrect_rratio 0.2)
			(net 1 "GND")
			(pinfunction "A")
			(pintype "passive")
		)
	)
	(footprint "antmicro-footprints:SOT-523"
		(layer "B.Cu")
		(at 225.5 109.2 180)
		(property "Reference" "Q19"
			(at 0.995 -3.4 270)
			(layer "B.SilkS")
			(effects
				(font
					(size 0.7 0.7)
					(thickness 0.15)
				)
				(justify right top mirror)
			)
		)
		(property "Value" "DMG1012T-7"
			(at 0.1 -1.824 0)
			(layer "B.Fab")
			(effects
				(font
					(size 0.7 0.7)
					(thickness 0.15)
				)
				(justify left bottom mirror)
			)
		)
		(property "Datasheet" "https://www.diodes.com/assets/Datasheets/ds31783.pdf"
			(at 0 0 0)
			(layer "B.Fab")
			(hide yes)
			(effects
				(font
					(size 1.27 1.27)
					(thickness 0.15)
				)
				(justify mirror)
			)
		)
		(property "Description" "Power MOSFET, N Channel, 20 V, 630 mA, 0.3 ohm, SOT-523, Surface Mount"
			(at 0 0 0)
			(layer "B.Fab")
			(hide yes)
			(effects
				(font
					(size 1.27 1.27)
					(thickness 0.15)
				)
				(justify mirror)
			)
		)
		(property "MPN" "DMG1012T-7"
			(at 0 0 0)
			(unlocked yes)
			(layer "B.Fab")
			(hide yes)
			(effects
				(font
					(size 1 1)
					(thickness 0.15)
				)
				(justify mirror)
			)
		)
		(property "Manufacturer" "Diodes Incorporated"
			(at 0 0 0)
			(unlocked yes)
			(layer "B.Fab")
			(hide yes)
			(effects
				(font
					(size 1 1)
					(thickness 0.15)
				)
				(justify mirror)
			)
		)
		(property "Author" "Antmicro"
			(at 0 0 0)
			(unlocked yes)
			(layer "B.Fab")
			(hide yes)
			(effects
				(font
					(size 1 1)
					(thickness 0.15)
				)
				(justify mirror)
			)
		)
		(property "License" "Apache-2.0"
			(at 0 0 0)
			(unlocked yes)
			(layer "B.Fab")
			(hide yes)
			(effects
				(font
					(size 1 1)
					(thickness 0.15)
				)
				(justify mirror)
			)
		)
		(sheetname "/Recovery USB/")
		(sheetfile "recovery_usb.kicad_sch")
		(attr smd)
		(fp_line
			(start -0.277 0.551)
			(end -0.277 0.75)
			(stroke
				(width 0.15)
				(type solid)
			)
			(layer "B.SilkS")
		)
		(fp_line
			(start -0.725 0.551)
			(end -0.277 0.551)
			(stroke
				(width 0.15)
				(type solid)
			)
			(layer "B.SilkS")
		)
		(fp_line
			(start -0.927 0.351)
			(end -0.725 0.551)
			(stroke
				(width 0.15)
				(type solid)
			)
			(layer "B.SilkS")
		)
		(fp_line
			(start -0.927 0.051)
			(end -0.927 0.351)
			(stroke
				(width 0.15)
				(type solid)
			)
			(layer "B.SilkS")
		)
		(fp_circle
			(center -0.9652 -0.9652)
			(end -0.9152 -0.9652)
			(stroke
				(width 0.15)
				(type solid)
			)
			(fill yes)
			(layer "B.SilkS")
		)
		(fp_line
			(start 1.1 1.16)
			(end 1.1 -1.15)
			(stroke
				(width 0.05)
				(type solid)
			)
			(layer "B.CrtYd")
		)
		(fp_line
			(start -1.12 1.16)
			(end 1.1 1.16)
			(stroke
				(width 0.05)
				(type solid)
			)
			(layer "B.CrtYd")
		)
		(fp_line
			(start -1.12 1.16)
			(end -1.12 -1.15)
			(stroke
				(width 0.05)
				(type solid)
			)
			(layer "B.CrtYd")
		)
		(fp_line
			(start -1.12 -1.15)
			(end 1.1 -1.15)
			(stroke
				(width 0.05)
				(type solid)
			)
			(layer "B.CrtYd")
		)
		(fp_line
			(start 0.8 0.425)
			(end 0.8 -0.424)
			(stroke
				(width 0.15)
				(type solid)
			)
			(layer "B.Fab")
		)
		(fp_line
			(start 0.8 0.425)
			(end -0.652 0.425)
			(stroke
				(width 0.15)
				(type solid)
			)
			(layer "B.Fab")
		)
		(fp_line
			(start 0.8 -0.424)
			(end -0.802 -0.424)
			(stroke
				(width 0.15)
				(type solid)
			)
			(layer "B.Fab")
		)
		(fp_line
			(start -0.652 0.425)
			(end -0.802 0.276)
			(stroke
				(width 0.15)
				(type solid)
			)
			(layer "B.Fab")
		)
		(fp_line
			(start -0.802 0.276)
			(end -0.802 -0.424)
			(stroke
				(width 0.15)
				(type solid)
			)
			(layer "B.Fab")
		)
		(fp_circle
			(center -0.9652 -0.9652)
			(end -0.9144 -0.9652)
			(stroke
				(width 0.15)
				(type solid)
			)
			(fill no)
			(layer "B.Fab")
		)
		(fp_text user "${REFERENCE}"
			(at -1.12 -3.824 0)
			(layer "B.Fab")
			(effects
				(font
					(size 0.7 0.7)
					(thickness 0.15)
				)
				(justify left bottom mirror)
			)
		)
		(fp_text user "License: Apache-2.0"
			(at -1.12 -5.024 0)
			(layer "B.Fab")
			(effects
				(font
					(size 0.7 0.7)
					(thickness 0.15)
				)
				(justify left bottom mirror)
			)
		)
		(fp_text user "Author: Antmicro"
			(at -1.12 -6.224 0)
			(layer "B.Fab")
			(effects
				(font
					(size 0.7 0.7)
					(thickness 0.15)
				)
				(justify left bottom mirror)
			)
		)
		(pad "1" smd rect
			(at -0.5 -0.65 180)
			(size 0.4 0.51)
			(layers "B.Cu" "B.Mask" "B.Paste")
			(net 889 "/Recovery USB/USBC2_ID")
			(pinfunction "G")
			(pintype "input")
		)
		(pad "2" smd rect
			(at 0.498 -0.65 180)
			(size 0.4 0.51)
			(layers "B.Cu" "B.Mask" "B.Paste")
			(net 1 "GND")
			(pinfunction "S")
			(pintype "passive")
		)
		(pad "3" smd rect
			(at 0 0.652 180)
			(size 0.4 0.51)
			(layers "B.Cu" "B.Mask" "B.Paste")
			(net 890 "Net-(Q19-D)")
			(pinfunction "D")
			(pintype "passive")
		)
	)
	(footprint "antmicro-footprints:USON-10_2.5x1mm_P0.5mm"
		(layer "B.Cu")
		(at 147.13 60.91 90)
		(descr "USON-10 2.5x1mm_ Pitch 0.5mm")
		(tags "USON-10 2.5x1mm Pitch 0.5mm")
		(property "Reference" "U68"
			(at -0.99 -0.03 0)
			(layer "B.SilkS")
			(effects
				(font
					(size 0.7 0.7)
					(thickness 0.15)
				)
				(justify right top mirror)
			)
		)
		(property "Value" "TPD4E05U06QDQARQ1"
			(at 0.018 -2.499 90)
			(layer "B.Fab")
			(effects
				(font
					(size 0.7 0.7)
					(thickness 0.15)
				)
				(justify right top mirror)
			)
		)
		(property "Datasheet" "https://www.ti.com/lit/ds/symlink/tpd4e05u06-q1.pdf?HQS=dis-mous-null-mousermode-dsf-pf-null-wwe&ts=1663591265741&ref_url=https%253A%252F%252Fwww.mouser.com%252F"
			(at 0 0 90)
			(layer "B.Fab")
			(hide yes)
			(effects
				(font
					(size 1.27 1.27)
					(thickness 0.15)
				)
				(justify mirror)
			)
		)
		(property "Description" "TVS diode array, 12 kV, USON-10, 5.5 V, 0.5 pF"
			(at 0 0 90)
			(layer "B.Fab")
			(hide yes)
			(effects
				(font
					(size 1.27 1.27)
					(thickness 0.15)
				)
				(justify mirror)
			)
		)
		(property "Manufacturer" "Texas Instruments"
			(at 0 0 270)
			(unlocked yes)
			(layer "B.Fab")
			(hide yes)
			(effects
				(font
					(size 1 1)
					(thickness 0.15)
				)
				(justify mirror)
			)
		)
		(property "MPN" "TPD4E05U06QDQARQ1"
			(at 0 0 270)
			(unlocked yes)
			(layer "B.Fab")
			(hide yes)
			(effects
				(font
					(size 1 1)
					(thickness 0.15)
				)
				(justify mirror)
			)
		)
		(property "Author" "Antmicro"
			(at 0 0 270)
			(unlocked yes)
			(layer "B.Fab")
			(hide yes)
			(effects
				(font
					(size 1 1)
					(thickness 0.15)
				)
				(justify mirror)
			)
		)
		(property "License" "Apache-2.0"
			(at 0 0 270)
			(unlocked yes)
			(layer "B.Fab")
			(hide yes)
			(effects
				(font
					(size 1 1)
					(thickness 0.15)
				)
				(justify mirror)
			)
		)
		(sheetname "/Peripherals/")
		(sheetfile "peripherals.kicad_sch")
		(attr smd)
		(fp_line
			(start 0.498 -1.398)
			(end -0.5 -1.398)
			(stroke
				(width 0.15)
				(type solid)
			)
			(layer "B.SilkS")
		)
		(fp_line
			(start 0.498 1.401)
			(end -0.5 1.401)
			(stroke
				(width 0.15)
				(type solid)
			)
			(layer "B.SilkS")
		)
		(fp_circle
			(center -0.68 1.27)
			(end -0.63 1.27)
			(stroke
				(width 0.15)
				(type solid)
			)
			(fill yes)
			(layer "B.SilkS")
		)
		(fp_rect
			(start -0.8 1.5)
			(end 0.8 -1.499)
			(stroke
				(width 0.05)
				(type solid)
			)
			(fill no)
			(layer "B.CrtYd")
		)
		(fp_line
			(start -0.5 -1.249)
			(end 0.498 -1.249)
			(stroke
				(width 0.15)
				(type solid)
			)
			(layer "B.Fab")
		)
		(fp_line
			(start -0.5 1)
			(end -0.5 -1.249)
			(stroke
				(width 0.15)
				(type solid)
			)
			(layer "B.Fab")
		)
		(fp_line
			(start 0.498 1.25)
			(end 0.498 -1.249)
			(stroke
				(width 0.15)
				(type solid)
			)
			(layer "B.Fab")
		)
		(fp_line
			(start 0.498 1.25)
			(end -0.25 1.25)
			(stroke
				(width 0.15)
				(type solid)
			)
			(layer "B.Fab")
		)
		(fp_line
			(start -0.25 1.25)
			(end -0.5 1)
			(stroke
				(width 0.15)
				(type solid)
			)
			(layer "B.Fab")
		)
		(fp_text user "Author: Antmicro"
			(at -0.802 -5.7 90)
			(layer "B.Fab")
			(effects
				(font
					(size 0.7 0.7)
					(thickness 0.15)
				)
				(justify right top mirror)
			)
		)
		(fp_text user "${REFERENCE}"
			(at -0.802 -4.498 90)
			(layer "B.Fab")
			(effects
				(font
					(size 0.7 0.7)
					(thickness 0.15)
				)
				(justify right top mirror)
			)
		)
		(fp_text user "License: Apache-2.0"
			(at -0.802 -6.9 90)
			(layer "B.Fab")
			(effects
				(font
					(size 0.7 0.7)
					(thickness 0.15)
				)
				(justify right top mirror)
			)
		)
		(pad "1" smd roundrect
			(at -0.387 1 180)
			(size 0.25 0.55)
			(layers "B.Cu" "B.Mask" "B.Paste")
			(roundrect_rratio 0.25)
			(net 42 "/Peripherals/I2C_{CONN}.SCL")
			(pintype "passive")
		)
		(pad "2" smd roundrect
			(at -0.387 0.5 180)
			(size 0.25 0.55)
			(layers "B.Cu" "B.Mask" "B.Paste")
			(roundrect_rratio 0.25)
			(net 43 "/Peripherals/I2C_{CONN}.SDA")
			(pintype "passive")
		)
		(pad "3" smd roundrect
			(at -0.387 0 180)
			(size 0.4 0.55)
			(layers "B.Cu" "B.Mask" "B.Paste")
			(roundrect_rratio 0.25)
			(net 1 "GND")
			(pintype "power_in")
		)
		(pad "4" smd roundrect
			(at -0.387 -0.498 180)
			(size 0.25 0.55)
			(layers "B.Cu" "B.Mask" "B.Paste")
			(roundrect_rratio 0.25)
			(net 839 "/Peripherals/I2C_CONN2_3V3")
			(pintype "passive")
		)
		(pad "5" smd roundrect
			(at -0.387 -0.998 180)
			(size 0.25 0.55)
			(layers "B.Cu" "B.Mask" "B.Paste")
			(roundrect_rratio 0.25)
			(net 1 "GND")
			(pintype "passive")
		)
		(pad "6" smd roundrect
			(at 0.385 -0.998 180)
			(size 0.25 0.55)
			(layers "B.Cu" "B.Mask" "B.Paste")
			(roundrect_rratio 0.25)
			(net 1 "GND")
			(pintype "passive")
		)
		(pad "7" smd roundrect
			(at 0.385 -0.498 180)
			(size 0.25 0.55)
			(layers "B.Cu" "B.Mask" "B.Paste")
			(roundrect_rratio 0.25)
			(net 839 "/Peripherals/I2C_CONN2_3V3")
			(pintype "passive")
		)
		(pad "8" smd roundrect
			(at 0.385 0 180)
			(size 0.4 0.55)
			(layers "B.Cu" "B.Mask" "B.Paste")
			(roundrect_rratio 0.25)
			(net 1 "GND")
			(pintype "passive")
		)
		(pad "9" smd roundrect
			(at 0.385 0.5 180)
			(size 0.25 0.55)
			(layers "B.Cu" "B.Mask" "B.Paste")
			(roundrect_rratio 0.25)
			(net 43 "/Peripherals/I2C_{CONN}.SDA")
			(pintype "passive")
		)
		(pad "10" smd roundrect
			(at 0.385 1 180)
			(size 0.25 0.55)
			(layers "B.Cu" "B.Mask" "B.Paste")
			(roundrect_rratio 0.25)
			(net 42 "/Peripherals/I2C_{CONN}.SCL")
			(pintype "passive")
		)
	)
)
